(kicad_pcb
	(version 20260206)
	(generator "pcbnew")
	(generator_version "10.0")
	(general
		(thickness 1.6)
		(legacy_teardrops no)
	)
	(paper "A4")
	(title_block
		(title "12092022_DA0F0TFB6D0_F0T_FAN_BOARD_MP5048_D_brd_v02_OCP.brd")
		(comment 1 "Grand Teton / footprints 37-43 of 924")
	)
	(layers
		(0 "F.Cu" signal "TOP")
		(4 "In1.Cu" signal "GND")
		(6 "In2.Cu" signal "IN1")
		(8 "In3.Cu" signal "IN2")
		(10 "In4.Cu" signal "GND1")
		(2 "B.Cu" signal "BOTTOM")
		(9 "F.Adhes" user "F.Adhesive")
		(11 "B.Adhes" user "B.Adhesive")
		(13 "F.Paste" user "Package Geometry/Pastemask Top")
		(15 "B.Paste" user "Package Geometry/Pastemask Bottom")
		(5 "F.SilkS" user "Ref Des/Silkscreen Top")
		(7 "B.SilkS" user "Ref Des/Silkscreen Bottom")
		(1 "F.Mask" user "Board Geometry/Soldermask Top")
		(3 "B.Mask" user "Board Geometry/Soldermask Bottom")
		(17 "Dwgs.User" user "User.Drawings")
		(19 "Cmts.User" user "User.Comments")
		(21 "Eco1.User" user "User.Eco1")
		(23 "Eco2.User" user "User.Eco2")
		(25 "Edge.Cuts" user "Board Geometry/Outline")
		(27 "Margin" user)
		(31 "F.CrtYd" user "Package Geometry/Place Bound Top")
		(29 "B.CrtYd" user "Package Geometry/Place Bound Bottom")
		(35 "F.Fab" user "Ref Des/Assembly Top")
		(33 "B.Fab" user "Ref Des/Assembly Bottom")
	)
	(footprint ""
		(layer "F.Cu")
		(at 36.195 -196.370956)
		(property "Reference" "D135"
			(at 2.286 0.944626 0)
			(unlocked yes)
			(layer "F.SilkS")
			(effects
				(font
					(size 0.7874 0.5842)
					(thickness 0.1524)
				)
				(justify left)
			)
		)
		(property "Value" ""
			(at 0 0 0)
			(layer "F.Fab")
			(effects
				(font
					(size 1.27 1.27)
				)
			)
		)
		(duplicate_pad_numbers_are_jumpers no)
		(fp_line
			(start -0.299974 -0.500126)
			(end -0.299974 0.500126)
			(stroke
				(width 0.1524)
				(type default)
			)
			(layer "F.SilkS")
		)
		(fp_line
			(start -0.299974 0.500126)
			(end 0.199898 0)
			(stroke
				(width 0.1524)
				(type default)
			)
			(layer "F.SilkS")
		)
		(fp_line
			(start 0.199898 0)
			(end -0.299974 -0.500126)
			(stroke
				(width 0.1524)
				(type default)
			)
			(layer "F.SilkS")
		)
		(fp_line
			(start 0.299974 -0.500126)
			(end 0.299974 0.500126)
			(stroke
				(width 0.1524)
				(type default)
			)
			(layer "F.SilkS")
		)
		(fp_line
			(start 1.651 -0.6858)
			(end 1.651 0.6858)
			(stroke
				(width 0.1524)
				(type default)
			)
			(layer "F.SilkS")
		)
		(fp_line
			(start 1.778 0.6858)
			(end 1.778 -0.6858)
			(stroke
				(width 0.1524)
				(type default)
			)
			(layer "F.SilkS")
		)
		(fp_line
			(start -1.35001 -0.225044)
			(end -0.899922 -0.225044)
			(stroke
				(width 0.1)
				(type default)
			)
			(layer "F.Fab")
		)
		(fp_line
			(start -1.35001 0.175006)
			(end -1.35001 -0.225044)
			(stroke
				(width 0.1)
				(type default)
			)
			(layer "F.Fab")
		)
		(fp_line
			(start -0.899922 -0.700024)
			(end 0.899922 -0.700024)
			(stroke
				(width 0.1)
				(type default)
			)
			(layer "F.Fab")
		)
		(fp_line
			(start -0.899922 -0.225044)
			(end -0.899922 -0.700024)
			(stroke
				(width 0.1)
				(type default)
			)
			(layer "F.Fab")
		)
		(fp_line
			(start -0.899922 0.175006)
			(end -1.35001 0.175006)
			(stroke
				(width 0.1)
				(type default)
			)
			(layer "F.Fab")
		)
		(fp_line
			(start -0.899922 0.700024)
			(end -0.899922 0.175006)
			(stroke
				(width 0.1)
				(type default)
			)
			(layer "F.Fab")
		)
		(fp_line
			(start -0.299974 -0.500126)
			(end -0.299974 0.500126)
			(stroke
				(width 0.1)
				(type default)
			)
			(layer "F.Fab")
		)
		(fp_line
			(start -0.299974 0.500126)
			(end 0.199898 0)
			(stroke
				(width 0.1)
				(type default)
			)
			(layer "F.Fab")
		)
		(fp_line
			(start 0.199898 0)
			(end -0.299974 -0.500126)
			(stroke
				(width 0.1)
				(type default)
			)
			(layer "F.Fab")
		)
		(fp_line
			(start 0.299974 -0.500126)
			(end 0.299974 0.500126)
			(stroke
				(width 0.1)
				(type default)
			)
			(layer "F.Fab")
		)
		(fp_line
			(start 0.899922 -0.700024)
			(end 0.899922 -0.225044)
			(stroke
				(width 0.1)
				(type default)
			)
			(layer "F.Fab")
		)
		(fp_line
			(start 0.899922 -0.225044)
			(end 1.35001 -0.225044)
			(stroke
				(width 0.1)
				(type default)
			)
			(layer "F.Fab")
		)
		(fp_line
			(start 0.899922 0.175006)
			(end 0.899922 0.700024)
			(stroke
				(width 0.1)
				(type default)
			)
			(layer "F.Fab")
		)
		(fp_line
			(start 0.899922 0.700024)
			(end -0.899922 0.700024)
			(stroke
				(width 0.1)
				(type default)
			)
			(layer "F.Fab")
		)
		(fp_line
			(start 1.35001 -0.225044)
			(end 1.35001 0.175006)
			(stroke
				(width 0.1)
				(type default)
			)
			(layer "F.Fab")
		)
		(fp_line
			(start 1.35001 0.175006)
			(end 0.899922 0.175006)
			(stroke
				(width 0.1)
				(type default)
			)
			(layer "F.Fab")
		)
		(fp_text user "+"
			(at -2.667 0.822706 0)
			(unlocked yes)
			(layer "F.SilkS")
			(effects
				(font
					(size 1.905 1.4224)
					(thickness 0.1524)
				)
				(justify left)
			)
		)
		(fp_text user "-"
			(at 0.762 0.822706 0)
			(unlocked yes)
			(layer "F.SilkS")
			(effects
				(font
					(size 1.905 1.4224)
					(thickness 0.1524)
				)
				(justify left)
			)
		)
		(fp_text user "+"
			(at -2.794 -0.19685 0)
			(unlocked yes)
			(layer "F.Fab")
			(effects
				(font
					(size 1.905 1.4224)
					(thickness 0.1524)
				)
				(justify left)
			)
		)
		(fp_text user "-"
			(at 1.8288 -0.24765 0)
			(unlocked yes)
			(layer "F.Fab")
			(effects
				(font
					(size 1.905 1.4224)
					(thickness 0.1524)
				)
				(justify left)
			)
		)
		(pad "1" smd rect
			(at -1.0922 0 180)
			(size 0.8128 0.8636)
			(layers "F.Cu" "F.Mask" "F.Paste")
			(net "FAN_1_TACH_OL_R")
		)
		(pad "2" smd rect
			(at 1.0922 0)
			(size 0.8128 0.8636)
			(layers "F.Cu" "F.Mask" "F.Paste")
			(net "FAN_1_TACH_OL_D")
		)
	)
	(footprint ""
		(layer "F.Cu")
		(at 36.703 -64.262 180)
		(property "Reference" "PR24"
			(at 0 0 180)
			(layer "F.SilkS")
			(hide yes)
			(effects
				(font
					(size 1.27 1.27)
				)
			)
		)
		(property "Value" ""
			(at 0 0 180)
			(layer "F.Fab")
			(effects
				(font
					(size 1.27 1.27)
				)
			)
		)
		(duplicate_pad_numbers_are_jumpers no)
		(fp_line
			(start 0.7874 0.4064)
			(end -0.7874 0.4064)
			(stroke
				(width 0.1524)
				(type default)
			)
			(layer "F.SilkS")
		)
		(fp_line
			(start 0.7874 -0.4064)
			(end 0.7874 0.4064)
			(stroke
				(width 0.1524)
				(type default)
			)
			(layer "F.SilkS")
		)
		(fp_line
			(start -0.7874 0.4064)
			(end -0.7874 -0.4064)
			(stroke
				(width 0.1524)
				(type default)
			)
			(layer "F.SilkS")
		)
		(fp_line
			(start -0.7874 -0.4064)
			(end 0.7874 -0.4064)
			(stroke
				(width 0.1524)
				(type default)
			)
			(layer "F.SilkS")
		)
		(fp_line
			(start 0.67945 0.3048)
			(end 0.120396 0.3048)
			(stroke
				(width 0.1)
				(type default)
			)
			(layer "F.Fab")
		)
		(fp_line
			(start 0.67945 -0.3048)
			(end 0.67945 0.3048)
			(stroke
				(width 0.1)
				(type default)
			)
			(layer "F.Fab")
		)
		(fp_line
			(start 0.12065 -0.2794)
			(end 0.12065 -0.3048)
			(stroke
				(width 0.1)
				(type default)
			)
			(layer "F.Fab")
		)
		(fp_line
			(start 0.12065 -0.3048)
			(end 0.67945 -0.3048)
			(stroke
				(width 0.1)
				(type default)
			)
			(layer "F.Fab")
		)
		(fp_line
			(start 0.120396 0.3048)
			(end 0.120396 0.2794)
			(stroke
				(width 0.1)
				(type default)
			)
			(layer "F.Fab")
		)
		(fp_line
			(start 0.120396 0.2794)
			(end -0.12065 0.2794)
			(stroke
				(width 0.1)
				(type default)
			)
			(layer "F.Fab")
		)
		(fp_line
			(start -0.12065 0.3048)
			(end -0.67945 0.3048)
			(stroke
				(width 0.1)
				(type default)
			)
			(layer "F.Fab")
		)
		(fp_line
			(start -0.12065 0.2794)
			(end -0.12065 0.3048)
			(stroke
				(width 0.1)
				(type default)
			)
			(layer "F.Fab")
		)
		(fp_line
			(start -0.12065 -0.2794)
			(end 0.12065 -0.2794)
			(stroke
				(width 0.1)
				(type default)
			)
			(layer "F.Fab")
		)
		(fp_line
			(start -0.12065 -0.305054)
			(end -0.12065 -0.2794)
			(stroke
				(width 0.1)
				(type default)
			)
			(layer "F.Fab")
		)
		(fp_line
			(start -0.67945 0.3048)
			(end -0.67945 -0.305054)
			(stroke
				(width 0.1)
				(type default)
			)
			(layer "F.Fab")
		)
		(fp_line
			(start -0.67945 -0.305054)
			(end -0.12065 -0.305054)
			(stroke
				(width 0.1)
				(type default)
			)
			(layer "F.Fab")
		)
		(pad "1" smd circle
			(at -0.40005 0 180)
			(size 0 0)
			(layers "F.Cu" "F.Mask" "F.Paste")
			(net "FAN_3_P3V_R")
		)
		(pad "2" smd circle
			(at 0.40005 0 180)
			(size 0 0)
			(layers "F.Cu" "F.Mask" "F.Paste")
			(net "FAN_3_MODE")
		)
	)
	(footprint ""
		(layer "F.Cu")
		(at 26.162 -18.796)
		(property "Reference" "U323"
			(at -1.524 1.93167 0)
			(unlocked yes)
			(layer "F.SilkS")
			(effects
				(font
					(size 0.7874 0.5842)
					(thickness 0.1524)
				)
				(justify left)
			)
		)
		(property "Value" ""
			(at 0 0 0)
			(layer "F.Fab")
			(effects
				(font
					(size 1.27 1.27)
				)
			)
		)
		(duplicate_pad_numbers_are_jumpers no)
		(fp_line
			(start -1.538478 -1.150874)
			(end -1.538478 1.150874)
			(stroke
				(width 0.1524)
				(type default)
			)
			(layer "F.SilkS")
		)
		(fp_line
			(start -1.538478 1.150874)
			(end 1.538478 1.150874)
			(stroke
				(width 0.1524)
				(type default)
			)
			(layer "F.SilkS")
		)
		(fp_line
			(start 1.538478 -1.150874)
			(end -1.538478 -1.150874)
			(stroke
				(width 0.1524)
				(type default)
			)
			(layer "F.SilkS")
		)
		(fp_line
			(start 1.538478 1.150874)
			(end 1.538478 -1.150874)
			(stroke
				(width 0.1524)
				(type default)
			)
			(layer "F.SilkS")
		)
		(fp_line
			(start -0.674878 -1.100074)
			(end -0.674878 1.100074)
			(stroke
				(width 0.1)
				(type default)
			)
			(layer "F.Fab")
		)
		(fp_line
			(start -0.674878 1.100074)
			(end 0.674878 1.100074)
			(stroke
				(width 0.1)
				(type default)
			)
			(layer "F.Fab")
		)
		(fp_line
			(start 0.674878 -1.100074)
			(end -0.674878 -1.100074)
			(stroke
				(width 0.1)
				(type default)
			)
			(layer "F.Fab")
		)
		(fp_line
			(start 0.674878 1.100074)
			(end 0.674878 -1.100074)
			(stroke
				(width 0.1)
				(type default)
			)
			(layer "F.Fab")
		)
		(pad "1" smd rect
			(at -0.94996 -0.649986 90)
			(size 0.7112 0.9144)
			(layers "F.Cu" "F.Mask" "F.Paste")
			(net "FAN_4_PWM_IL")
		)
		(pad "2" smd rect
			(at -0.94996 0.649986 90)
			(size 0.7112 0.9144)
			(layers "F.Cu" "F.Mask" "F.Paste")
			(net "FAN_4_PWM_OL")
		)
		(pad "3" smd rect
			(at 0.94996 0 90)
			(size 0.7112 0.9144)
			(layers "F.Cu" "F.Mask" "F.Paste")
			(net "FAN_4_PWM_BUF")
		)
	)
	(footprint ""
		(layer "F.Cu")
		(at 15.377922 -119.476012 180)
		(property "Reference" "D247"
			(at 5.471922 1.528318 0)
			(unlocked yes)
			(layer "F.SilkS")
			(effects
				(font
					(size 0.7874 0.5842)
					(thickness 0.1524)
				)
				(justify left)
			)
		)
		(property "Value" ""
			(at 0 0 180)
			(layer "F.Fab")
			(effects
				(font
					(size 1.27 1.27)
				)
			)
		)
		(duplicate_pad_numbers_are_jumpers no)
		(fp_line
			(start 0.94488 0.450088)
			(end 0.94488 -0.450088)
			(stroke
				(width 0.1524)
				(type default)
			)
			(layer "F.SilkS")
		)
		(fp_line
			(start 0.94488 -0.450088)
			(end -0.854964 -0.450088)
			(stroke
				(width 0.1524)
				(type default)
			)
			(layer "F.SilkS")
		)
		(fp_line
			(start 0.870458 -0.2794)
			(end 0.845058 0.4064)
			(stroke
				(width 0.1524)
				(type default)
			)
			(layer "F.SilkS")
		)
		(fp_line
			(start 0.845058 0.4064)
			(end 0.845058 -0.381)
			(stroke
				(width 0.1524)
				(type default)
			)
			(layer "F.SilkS")
		)
		(fp_line
			(start -0.854964 0.450088)
			(end 0.925068 0.450088)
			(stroke
				(width 0.1524)
				(type default)
			)
			(layer "F.SilkS")
		)
		(fp_line
			(start -0.854964 -0.450088)
			(end -0.854964 0.450088)
			(stroke
				(width 0.1524)
				(type default)
			)
			(layer "F.SilkS")
		)
		(fp_line
			(start 0.54991 0.350012)
			(end 0.54991 -0.350012)
			(stroke
				(width 0.1)
				(type default)
			)
			(layer "F.Fab")
		)
		(fp_line
			(start 0.54991 -0.350012)
			(end -0.54991 -0.350012)
			(stroke
				(width 0.1)
				(type default)
			)
			(layer "F.Fab")
		)
		(fp_line
			(start -0.54991 0.350012)
			(end 0.54991 0.350012)
			(stroke
				(width 0.1)
				(type default)
			)
			(layer "F.Fab")
		)
		(fp_line
			(start -0.54991 -0.350012)
			(end -0.54991 0.350012)
			(stroke
				(width 0.1)
				(type default)
			)
			(layer "F.Fab")
		)
		(fp_text user "-"
			(at 2.423922 0.253238 0)
			(unlocked yes)
			(layer "F.SilkS")
			(effects
				(font
					(size 1.905 1.4224)
					(thickness 0.1524)
				)
				(justify left)
			)
		)
		(fp_text user "+"
			(at -0.497078 1.015238 0)
			(unlocked yes)
			(layer "F.SilkS")
			(effects
				(font
					(size 1.905 1.4224)
					(thickness 0.1524)
				)
				(justify left)
			)
		)
		(fp_text user "-"
			(at 2.48539 0.239014 0)
			(unlocked yes)
			(layer "F.Fab")
			(effects
				(font
					(size 1.905 1.4224)
					(thickness 0.1524)
				)
				(justify left)
			)
		)
		(fp_text user "+"
			(at -0.808228 0.239014 0)
			(unlocked yes)
			(layer "F.Fab")
			(effects
				(font
					(size 1.905 1.4224)
					(thickness 0.1524)
				)
				(justify left)
			)
		)
		(pad "A" smd rect
			(at -0.424942 0 180)
			(size 0.5588 0.6096)
			(layers "F.Cu" "F.Mask" "F.Paste")
			(net "GND")
		)
		(pad "C" smd rect
			(at 0.424942 0)
			(size 0.5588 0.6096)
			(layers "F.Cu" "F.Mask" "F.Paste")
			(net "FAN_5_TACH_OL_D")
		)
	)
	(footprint ""
		(layer "F.Cu")
		(at 40.850058 -157.661102)
		(property "Reference" "H4"
			(at -0.464058 17.225772 0)
			(unlocked yes)
			(layer "F.SilkS")
			(effects
				(font
					(size 0.7874 0.5842)
					(thickness 0.1524)
				)
				(justify left)
			)
		)
		(property "Value" ""
			(at 0 0 0)
			(layer "F.Fab")
			(effects
				(font
					(size 1.27 1.27)
				)
			)
		)
		(duplicate_pad_numbers_are_jumpers no)
		(pad "1" thru_hole oval
			(at 0 0)
			(size 9.017 21.0058)
			(drill 3.0226
				(offset 0 5.999988)
			)
			(layers "*.Cu" "*.Mask")
			(remove_unused_layers no)
			(net "GND")
			(clearance -1.500378)
			(padstack
				(mode front_inner_back)
				(layer "Inner"
					(shape circle)
					(size 0 0)
					(clearance 0)
				)
				(layer "B.Cu"
					(shape oval)
					(size 9.017 21.0058)
					(offset 0 5.999988)
					(clearance -1.500378)
				)
			)
		)
	)
	(footprint ""
		(layer "F.Cu")
		(at 16.51 -304.419 90)
		(property "Reference" "C2059"
			(at 0 0 90)
			(layer "F.SilkS")
			(hide yes)
			(effects
				(font
					(size 1.27 1.27)
				)
			)
		)
		(property "Value" ""
			(at 0 0 90)
			(layer "F.Fab")
			(effects
				(font
					(size 1.27 1.27)
				)
			)
		)
		(duplicate_pad_numbers_are_jumpers no)
		(fp_line
			(start 0.7874 -0.4064)
			(end 0.7874 0.4064)
			(stroke
				(width 0.1524)
				(type default)
			)
			(layer "F.SilkS")
		)
		(fp_line
			(start -0.7874 -0.4064)
			(end 0.7874 -0.4064)
			(stroke
				(width 0.1524)
				(type default)
			)
			(layer "F.SilkS")
		)
		(fp_line
			(start 0.7874 0.4064)
			(end -0.7874 0.4064)
			(stroke
				(width 0.1524)
				(type default)
			)
			(layer "F.SilkS")
		)
		(fp_line
			(start -0.7874 0.4064)
			(end -0.7874 -0.4064)
			(stroke
				(width 0.1524)
				(type default)
			)
			(layer "F.SilkS")
		)
		(fp_line
			(start -0.12065 -0.305054)
			(end -0.12065 -0.2794)
			(stroke
				(width 0.1)
				(type default)
			)
			(layer "F.Fab")
		)
		(fp_line
			(start -0.67945 -0.305054)
			(end -0.12065 -0.305054)
			(stroke
				(width 0.1)
				(type default)
			)
			(layer "F.Fab")
		)
		(fp_line
			(start 0.67945 -0.3048)
			(end 0.67945 0.3048)
			(stroke
				(width 0.1)
				(type default)
			)
			(layer "F.Fab")
		)
		(fp_line
			(start 0.12065 -0.3048)
			(end 0.67945 -0.3048)
			(stroke
				(width 0.1)
				(type default)
			)
			(layer "F.Fab")
		)
		(fp_line
			(start 0.12065 -0.2794)
			(end 0.12065 -0.3048)
			(stroke
				(width 0.1)
				(type default)
			)
			(layer "F.Fab")
		)
		(fp_line
			(start -0.12065 -0.2794)
			(end 0.12065 -0.2794)
			(stroke
				(width 0.1)
				(type default)
			)
			(layer "F.Fab")
		)
		(fp_line
			(start 0.120396 0.2794)
			(end -0.12065 0.2794)
			(stroke
				(width 0.1)
				(type default)
			)
			(layer "F.Fab")
		)
		(fp_line
			(start -0.12065 0.2794)
			(end -0.12065 0.3048)
			(stroke
				(width 0.1)
				(type default)
			)
			(layer "F.Fab")
		)
		(fp_line
			(start 0.67945 0.3048)
			(end 0.120396 0.3048)
			(stroke
				(width 0.1)
				(type default)
			)
			(layer "F.Fab")
		)
		(fp_line
			(start 0.120396 0.3048)
			(end 0.120396 0.2794)
			(stroke
				(width 0.1)
				(type default)
			)
			(layer "F.Fab")
		)
		(fp_line
			(start -0.12065 0.3048)
			(end -0.67945 0.3048)
			(stroke
				(width 0.1)
				(type default)
			)
			(layer "F.Fab")
		)
		(fp_line
			(start -0.67945 0.3048)
			(end -0.67945 -0.305054)
			(stroke
				(width 0.1)
				(type default)
			)
			(layer "F.Fab")
		)
		(pad "1" smd circle
			(at -0.40005 0 90)
			(size 0 0)
			(layers "F.Cu" "F.Mask" "F.Paste")
			(net "FAN_7_TACH_OL_R")
		)
		(pad "2" smd circle
			(at 0.40005 0 90)
			(size 0 0)
			(layers "F.Cu" "F.Mask" "F.Paste")
			(net "GND")
		)
	)
	(footprint ""
		(layer "F.Cu")
		(at 14.732 -259.08)
		(property "Reference" "PR73"
			(at 0 0 0)
			(layer "F.SilkS")
			(hide yes)
			(effects
				(font
					(size 1.27 1.27)
				)
			)
		)
		(property "Value" ""
			(at 0 0 0)
			(layer "F.Fab")
			(effects
				(font
					(size 1.27 1.27)
				)
			)
		)
		(duplicate_pad_numbers_are_jumpers no)
		(fp_line
			(start -0.7874 -0.4064)
			(end 0.7874 -0.4064)
			(stroke
				(width 0.1524)
				(type default)
			)
			(layer "F.SilkS")
		)
		(fp_line
			(start -0.7874 0.4064)
			(end -0.7874 -0.4064)
			(stroke
				(width 0.1524)
				(type default)
			)
			(layer "F.SilkS")
		)
		(fp_line
			(start 0.7874 -0.4064)
			(end 0.7874 0.4064)
			(stroke
				(width 0.1524)
				(type default)
			)
			(layer "F.SilkS")
		)
		(fp_line
			(start 0.7874 0.4064)
			(end -0.7874 0.4064)
			(stroke
				(width 0.1524)
				(type default)
			)
			(layer "F.SilkS")
		)
		(fp_line
			(start -0.67945 -0.305054)
			(end -0.12065 -0.305054)
			(stroke
				(width 0.1)
				(type default)
			)
			(layer "F.Fab")
		)
		(fp_line
			(start -0.67945 0.3048)
			(end -0.67945 -0.305054)
			(stroke
				(width 0.1)
				(type default)
			)
			(layer "F.Fab")
		)
		(fp_line
			(start -0.12065 -0.305054)
			(end -0.12065 -0.2794)
			(stroke
				(width 0.1)
				(type default)
			)
			(layer "F.Fab")
		)
		(fp_line
			(start -0.12065 -0.2794)
			(end 0.12065 -0.2794)
			(stroke
				(width 0.1)
				(type default)
			)
			(layer "F.Fab")
		)
		(fp_line
			(start -0.12065 0.2794)
			(end -0.12065 0.3048)
			(stroke
				(width 0.1)
				(type default)
			)
			(layer "F.Fab")
		)
		(fp_line
			(start -0.12065 0.3048)
			(end -0.67945 0.3048)
			(stroke
				(width 0.1)
				(type default)
			)
			(layer "F.Fab")
		)
		(fp_line
			(start 0.120396 0.2794)
			(end -0.12065 0.2794)
			(stroke
				(width 0.1)
				(type default)
			)
			(layer "F.Fab")
		)
		(fp_line
			(start 0.120396 0.3048)
			(end 0.120396 0.2794)
			(stroke
				(width 0.1)
				(type default)
			)
			(layer "F.Fab")
		)
		(fp_line
			(start 0.12065 -0.3048)
			(end 0.67945 -0.3048)
			(stroke
				(width 0.1)
				(type default)
			)
			(layer "F.Fab")
		)
		(fp_line
			(start 0.12065 -0.2794)
			(end 0.12065 -0.3048)
			(stroke
				(width 0.1)
				(type default)
			)
			(layer "F.Fab")
		)
		(fp_line
			(start 0.67945 -0.3048)
			(end 0.67945 0.3048)
			(stroke
				(width 0.1)
				(type default)
			)
			(layer "F.Fab")
		)
		(fp_line
			(start 0.67945 0.3048)
			(end 0.120396 0.3048)
			(stroke
				(width 0.1)
				(type default)
			)
			(layer "F.Fab")
		)
		(pad "1" smd circle
			(at -0.40005 0)
			(size 0 0)
			(layers "F.Cu" "F.Mask" "F.Paste")
			(net "FAN_7_P3V_R")
		)
		(pad "2" smd circle
			(at 0.40005 0)
			(size 0 0)
			(layers "F.Cu" "F.Mask" "F.Paste")
			(net "FAN_7_MODE")
		)
	)
)
